(kicad_pcb
	(version 20241229)
	(generator "pcbnew")
	(generator_version "9.0")
	(general
		(thickness 1.6296)
		(legacy_teardrops no)
	)
	(paper "A3")
	(title_block
		(title "Thunderbolt to 10GbE adapter")
		(date "2026-04-21")
		(rev "1.1.0")
		(company "Antmicro Ltd")
		(comment 1 "www.antmicro.com")
		(comment 9 "footprints 564-568 of 703")
	)
	(layers
		(0 "F.Cu" signal)
		(4 "In1.Cu" signal)
		(6 "In2.Cu" signal)
		(8 "In3.Cu" signal)
		(10 "In4.Cu" signal)
		(12 "In5.Cu" signal)
		(14 "In6.Cu" signal)
		(2 "B.Cu" signal)
		(9 "F.Adhes" user "F.Adhesive")
		(11 "B.Adhes" user "B.Adhesive")
		(13 "F.Paste" user)
		(15 "B.Paste" user)
		(5 "F.SilkS" user "F.Silkscreen")
		(7 "B.SilkS" user "B.Silkscreen")
		(1 "F.Mask" user)
		(3 "B.Mask" user)
		(17 "Dwgs.User" user "User.Drawings")
		(19 "Cmts.User" user "User.Comments")
		(21 "Eco1.User" user "User.Eco1")
		(23 "Eco2.User" user "User.Eco2")
		(25 "Edge.Cuts" user)
		(27 "Margin" user)
		(31 "F.CrtYd" user "F.Courtyard")
		(29 "B.CrtYd" user "B.Courtyard")
		(35 "F.Fab" user)
		(33 "B.Fab" user)
	)
	(footprint "antmicro-footprints:R_0402_1005Metric"
		(layer "B.Cu")
		(at 136.5 123.15)
		(descr "Resistor SMD 0402")
		(tags "resistor SMD 0402")
		(property "Reference" "R49"
			(at 19.525001 -7.450001 180)
			(layer "B.SilkS")
			(effects
				(font
					(size 0.7 0.7)
					(thickness 0.15)
				)
				(justify mirror)
			)
		)
		(property "Value" "R_10k_0402"
			(at -1.011843 -1.772047 180)
			(layer "B.Fab")
			(effects
				(font
					(size 0.7 0.7)
					(thickness 0.15)
				)
				(justify left bottom mirror)
			)
		)
		(property "Datasheet" "https://www.bourns.com/docs/product-datasheets/cr.pdf"
			(at 0 0 180)
			(layer "B.Fab")
			(hide yes)
			(effects
				(font
					(size 1.27 1.27)
					(thickness 0.15)
				)
				(justify mirror)
			)
		)
		(property "Description" "SMD Chip Resistor, 10 kohm, ± 1%, 62.5 mW, 0402 [1005 Metric], Thick Film, General Purpose"
			(at 0 0 180)
			(layer "B.Fab")
			(hide yes)
			(effects
				(font
					(size 1.27 1.27)
					(thickness 0.15)
				)
				(justify mirror)
			)
		)
		(property "MPN" "CR0402-FX-1002GLF"
			(at 0 0 0)
			(unlocked yes)
			(layer "B.Fab")
			(hide yes)
			(effects
				(font
					(size 1 1)
					(thickness 0.15)
				)
				(justify mirror)
			)
		)
		(property "Manufacturer" "Bourns"
			(at 0 0 0)
			(unlocked yes)
			(layer "B.Fab")
			(hide yes)
			(effects
				(font
					(size 1 1)
					(thickness 0.15)
				)
				(justify mirror)
			)
		)
		(property "License" "Apache-2.0"
			(at 0 0 0)
			(unlocked yes)
			(layer "B.Fab")
			(hide yes)
			(effects
				(font
					(size 1 1)
					(thickness 0.15)
				)
				(justify mirror)
			)
		)
		(property "Val" "10k"
			(at 0 0 0)
			(unlocked yes)
			(layer "B.Fab")
			(hide yes)
			(effects
				(font
					(size 1 1)
					(thickness 0.15)
				)
				(justify mirror)
			)
		)
		(property "Tolerance" "1%"
			(at 0 0 0)
			(unlocked yes)
			(layer "B.Fab")
			(hide yes)
			(effects
				(font
					(size 1 1)
					(thickness 0.15)
				)
				(justify mirror)
			)
		)
		(property "Author" "Antmicro"
			(at 0 0 0)
			(unlocked yes)
			(layer "B.Fab")
			(hide yes)
			(effects
				(font
					(size 1 1)
					(thickness 0.15)
				)
				(justify mirror)
			)
		)
		(sheetname "/TB Controller/")
		(sheetfile "tb.kicad_sch")
		(attr smd)
		(fp_rect
			(start -0.925 0.47)
			(end 0.925 -0.47)
			(stroke
				(width 0.05)
				(type default)
			)
			(fill no)
			(layer "B.CrtYd")
		)
		(fp_rect
			(start -0.5 0.25)
			(end 0.5 -0.25)
			(stroke
				(width 0.15)
				(type solid)
			)
			(fill no)
			(layer "B.Fab")
		)
		(fp_text user "License: Apache-2.0"
			(at -0.95 -5.169 180)
			(layer "B.Fab")
			(effects
				(font
					(size 0.7 0.7)
					(thickness 0.15)
				)
				(justify left bottom mirror)
			)
		)
		(fp_text user "${REFERENCE}"
			(at -0.95 -3.168 180)
			(layer "B.Fab")
			(effects
				(font
					(size 0.7 0.7)
					(thickness 0.15)
				)
				(justify left bottom mirror)
			)
		)
		(fp_text user "Author: Antmicro"
			(at -0.95 -4.169 180)
			(layer "B.Fab")
			(effects
				(font
					(size 0.7 0.7)
					(thickness 0.15)
				)
				(justify left bottom mirror)
			)
		)
		(pad "1" smd roundrect
			(at -0.48 0)
			(size 0.59 0.64)
			(layers "B.Cu" "B.Mask" "B.Paste")
			(roundrect_rratio 0.25)
			(net 192 "Net-(U4C-POC_GPIO_1)")
			(pintype "passive")
		)
		(pad "2" smd roundrect
			(at 0.48 0)
			(size 0.59 0.64)
			(layers "B.Cu" "B.Mask" "B.Paste")
			(roundrect_rratio 0.25)
			(net 57 "+3V3_TB")
			(pintype "passive")
		)
	)
	(footprint "antmicro-footprints:C_Pol_EIA-A"
		(layer "B.Cu")
		(at 161 103 -90)
		(property "Reference" "C326"
			(at -5 -0.5 90)
			(layer "B.SilkS")
			(effects
				(font
					(size 0.7 0.7)
					(thickness 0.15)
				)
				(justify left bottom mirror)
			)
		)
		(property "Value" "C_Pol_100u_6V_KEMET-T490-A"
			(at 0 -2 90)
			(layer "B.Fab")
			(effects
				(font
					(size 0.7 0.7)
					(thickness 0.15)
				)
				(justify left bottom mirror)
			)
		)
		(property "Datasheet" "https://www.kemet.com/en/us/capacitors/product/T490A107M006ATE800.html"
			(at 0 0 90)
			(layer "B.Fab")
			(hide yes)
			(effects
				(font
					(size 1.27 1.27)
					(thickness 0.15)
				)
				(justify mirror)
			)
		)
		(property "Description" "Surface Mount Tantalum Capacitor,  Solid SMD 6V 100uF 1206 20% ESR=800mOhms"
			(at 0 0 90)
			(layer "B.Fab")
			(hide yes)
			(effects
				(font
					(size 1.27 1.27)
					(thickness 0.15)
				)
				(justify mirror)
			)
		)
		(property "Val" "100u"
			(at 0 0 270)
			(unlocked yes)
			(layer "B.Fab")
			(hide yes)
			(effects
				(font
					(size 1 1)
					(thickness 0.15)
				)
				(justify mirror)
			)
		)
		(property "MPN" "T490A107M006ATE800"
			(at 0 0 270)
			(unlocked yes)
			(layer "B.Fab")
			(hide yes)
			(effects
				(font
					(size 1 1)
					(thickness 0.15)
				)
				(justify mirror)
			)
		)
		(property "Manufacturer" "KEMET"
			(at 0 0 270)
			(unlocked yes)
			(layer "B.Fab")
			(hide yes)
			(effects
				(font
					(size 1 1)
					(thickness 0.15)
				)
				(justify mirror)
			)
		)
		(property "License" "Apache-2.0"
			(at 0 0 270)
			(unlocked yes)
			(layer "B.Fab")
			(hide yes)
			(effects
				(font
					(size 1 1)
					(thickness 0.15)
				)
				(justify mirror)
			)
		)
		(property "Author" "Antmicro"
			(at 0 0 270)
			(unlocked yes)
			(layer "B.Fab")
			(hide yes)
			(effects
				(font
					(size 1 1)
					(thickness 0.15)
				)
				(justify mirror)
			)
		)
		(property "Voltage" "6V"
			(at 0 0 270)
			(unlocked yes)
			(layer "B.Fab")
			(hide yes)
			(effects
				(font
					(size 1 1)
					(thickness 0.15)
				)
				(justify mirror)
			)
		)
		(property "Dielectric" "template_dielectric"
			(at 0 0 270)
			(unlocked yes)
			(layer "B.Fab")
			(hide yes)
			(effects
				(font
					(size 1 1)
					(thickness 0.15)
				)
				(justify mirror)
			)
		)
		(sheetname "/X710-AT2 power/")
		(sheetfile "x710-at2-power.kicad_sch")
		(attr smd)
		(fp_line
			(start -1.95 1.25)
			(end -1.95 0.95)
			(stroke
				(width 0.12)
				(type solid)
			)
			(layer "B.SilkS")
		)
		(fp_line
			(start -2.1 1.1)
			(end -1.8 1.1)
			(stroke
				(width 0.12)
				(type solid)
			)
			(layer "B.SilkS")
		)
		(fp_line
			(start -1.5 0.85)
			(end 1.5 0.85)
			(stroke
				(width 0.12)
				(type solid)
			)
			(layer "B.SilkS")
		)
		(fp_line
			(start -1.5 0.75)
			(end -1.5 0.85)
			(stroke
				(width 0.12)
				(type solid)
			)
			(layer "B.SilkS")
		)
		(fp_line
			(start 1.5 0.75)
			(end 1.5 0.85)
			(stroke
				(width 0.12)
				(type solid)
			)
			(layer "B.SilkS")
		)
		(fp_line
			(start -1.5 -0.75)
			(end -1.5 -0.85)
			(stroke
				(width 0.12)
				(type solid)
			)
			(layer "B.SilkS")
		)
		(fp_line
			(start 1.5 -0.75)
			(end 1.5 -0.85)
			(stroke
				(width 0.12)
				(type solid)
			)
			(layer "B.SilkS")
		)
		(fp_line
			(start 1.5 -0.85)
			(end -1.5 -0.85)
			(stroke
				(width 0.12)
				(type solid)
			)
			(layer "B.SilkS")
		)
		(fp_line
			(start 1.7 1.05)
			(end -1.7 1.05)
			(stroke
				(width 0.05)
				(type solid)
			)
			(layer "B.CrtYd")
		)
		(fp_line
			(start -2.05 0.85)
			(end -2.05 -0.85)
			(stroke
				(width 0.05)
				(type solid)
			)
			(layer "B.CrtYd")
		)
		(fp_line
			(start -1.7 0.85)
			(end -1.7 1.05)
			(stroke
				(width 0.05)
				(type solid)
			)
			(layer "B.CrtYd")
		)
		(fp_line
			(start -1.7 0.85)
			(end -2.05 0.85)
			(stroke
				(width 0.05)
				(type solid)
			)
			(layer "B.CrtYd")
		)
		(fp_line
			(start 1.7 0.85)
			(end 1.7 1.05)
			(stroke
				(width 0.05)
				(type solid)
			)
			(layer "B.CrtYd")
		)
		(fp_line
			(start 2.05 0.85)
			(end 1.7 0.85)
			(stroke
				(width 0.05)
				(type solid)
			)
			(layer "B.CrtYd")
		)
		(fp_line
			(start 2.05 0.85)
			(end 2.05 -0.85)
			(stroke
				(width 0.05)
				(type solid)
			)
			(layer "B.CrtYd")
		)
		(fp_line
			(start -1.7 -0.85)
			(end -2.05 -0.85)
			(stroke
				(width 0.05)
				(type solid)
			)
			(layer "B.CrtYd")
		)
		(fp_line
			(start 2.05 -0.85)
			(end 1.7 -0.85)
			(stroke
				(width 0.05)
				(type solid)
			)
			(layer "B.CrtYd")
		)
		(fp_line
			(start -1.7 -1.05)
			(end -1.7 -0.85)
			(stroke
				(width 0.05)
				(type solid)
			)
			(layer "B.CrtYd")
		)
		(fp_line
			(start 1.7 -1.05)
			(end 1.7 -0.85)
			(stroke
				(width 0.05)
				(type solid)
			)
			(layer "B.CrtYd")
		)
		(fp_line
			(start 1.7 -1.05)
			(end -1.7 -1.05)
			(stroke
				(width 0.05)
				(type solid)
			)
			(layer "B.CrtYd")
		)
		(fp_rect
			(start -1.601 0.802)
			(end 1.6 -0.8)
			(stroke
				(width 0.1)
				(type solid)
			)
			(fill no)
			(layer "B.Fab")
		)
		(fp_text user "Author: Antmicro"
			(at -2.1 -6.198 90)
			(layer "B.Fab")
			(effects
				(font
					(size 0.7 0.7)
					(thickness 0.15)
				)
				(justify left bottom mirror)
			)
		)
		(fp_text user "${REFERENCE}"
			(at -2.1 -4.198 90)
			(layer "B.Fab")
			(effects
				(font
					(size 0.7 0.7)
					(thickness 0.15)
				)
				(justify left bottom mirror)
			)
		)
		(fp_text user "License: Apache-2.0"
			(at -2.1 -5.198 90)
			(layer "B.Fab")
			(effects
				(font
					(size 0.7 0.7)
					(thickness 0.15)
				)
				(justify left bottom mirror)
			)
		)
		(pad "1" smd roundrect
			(at -1.2 0 270)
			(size 1.2 1.2)
			(layers "B.Cu" "B.Mask" "B.Paste")
			(roundrect_rratio 0.1)
			(net 136 "+1V0")
			(pintype "passive")
		)
		(pad "2" smd roundrect
			(at 1.2 0 270)
			(size 1.2 1.2)
			(layers "B.Cu" "B.Mask" "B.Paste")
			(roundrect_rratio 0.1)
			(net 23 "GND")
			(pintype "passive")
		)
	)
	(footprint "antmicro-footprints:SOD-523"
		(layer "B.Cu")
		(at 121.5 76)
		(property "Reference" "D12"
			(at 0.9 -0.8 180)
			(layer "B.SilkS")
			(effects
				(font
					(size 0.7 0.7)
					(thickness 0.15)
				)
				(justify left bottom mirror)
			)
		)
		(property "Value" "PESD5Z5_0F"
			(at 0 -1.499 180)
			(layer "B.Fab")
			(effects
				(font
					(size 0.7 0.7)
					(thickness 0.15)
				)
				(justify left bottom mirror)
			)
		)
		(property "Datasheet" "https://assets.nexperia.com/documents/data-sheet/PESD5Z5_0.pdf"
			(at 0 0 180)
			(layer "B.Fab")
			(hide yes)
			(effects
				(font
					(size 1.27 1.27)
					(thickness 0.15)
				)
				(justify mirror)
			)
		)
		(property "Description" "Unidirectional TVS, 30 kV,  SOD-523, 5 V, 89 pF"
			(at 0 0 180)
			(layer "B.Fab")
			(hide yes)
			(effects
				(font
					(size 1.27 1.27)
					(thickness 0.15)
				)
				(justify mirror)
			)
		)
		(property "Manufacturer" "Nexperia"
			(at 0 0 0)
			(unlocked yes)
			(layer "B.Fab")
			(hide yes)
			(effects
				(font
					(size 1 1)
					(thickness 0.15)
				)
				(justify mirror)
			)
		)
		(property "MPN" "PESD5Z5.0F"
			(at 0 0 0)
			(unlocked yes)
			(layer "B.Fab")
			(hide yes)
			(effects
				(font
					(size 1 1)
					(thickness 0.15)
				)
				(justify mirror)
			)
		)
		(property "Author" "Antmicro"
			(at 0 0 0)
			(unlocked yes)
			(layer "B.Fab")
			(hide yes)
			(effects
				(font
					(size 1 1)
					(thickness 0.15)
				)
				(justify mirror)
			)
		)
		(property "License" "Apache-2.0"
			(at 0 0 0)
			(unlocked yes)
			(layer "B.Fab")
			(hide yes)
			(effects
				(font
					(size 1 1)
					(thickness 0.15)
				)
				(justify mirror)
			)
		)
		(sheetname "/Fan controller/")
		(sheetfile "fan-controller.kicad_sch")
		(attr smd)
		(fp_line
			(start -0.35 0.5)
			(end -0.35 -0.5)
			(stroke
				(width 0.15)
				(type solid)
			)
			(layer "B.SilkS")
		)
		(fp_rect
			(start -1 0.6)
			(end 1 -0.6)
			(stroke
				(width 0.05)
				(type solid)
			)
			(fill no)
			(layer "B.CrtYd")
		)
		(fp_line
			(start -0.652 -0.423)
			(end -0.652 0.425)
			(stroke
				(width 0.15)
				(type solid)
			)
			(layer "B.Fab")
		)
		(fp_line
			(start -0.652 -0.423)
			(end 0.65 -0.423)
			(stroke
				(width 0.15)
				(type solid)
			)
			(layer "B.Fab")
		)
		(fp_line
			(start -0.652 0.425)
			(end 0.65 0.425)
			(stroke
				(width 0.15)
				(type solid)
			)
			(layer "B.Fab")
		)
		(fp_line
			(start -0.35 0.4)
			(end -0.35 -0.4)
			(stroke
				(width 0.15)
				(type solid)
			)
			(layer "B.Fab")
		)
		(fp_line
			(start 0.65 0.425)
			(end 0.65 -0.423)
			(stroke
				(width 0.15)
				(type solid)
			)
			(layer "B.Fab")
		)
		(fp_text user "Author: Antmicro"
			(at -1.276 -4.7 180)
			(layer "B.Fab")
			(effects
				(font
					(size 0.7 0.7)
					(thickness 0.15)
				)
				(justify left bottom mirror)
			)
		)
		(fp_text user "${REFERENCE}"
			(at -1.276 -3.499 180)
			(layer "B.Fab")
			(effects
				(font
					(size 0.7 0.7)
					(thickness 0.15)
				)
				(justify left bottom mirror)
			)
		)
		(fp_text user "License: Apache-2.0"
			(at -1.276 -5.9 180)
			(layer "B.Fab")
			(effects
				(font
					(size 0.7 0.7)
					(thickness 0.15)
				)
				(justify left bottom mirror)
			)
		)
		(pad "1" smd roundrect
			(at -0.701 0)
			(size 0.5 0.6)
			(layers "B.Cu" "B.Mask" "B.Paste")
			(roundrect_rratio 0.25)
			(net 154 "/Fan controller/PWM")
			(pinfunction "C")
			(pintype "passive")
		)
		(pad "2" smd roundrect
			(at 0.699 0)
			(size 0.5 0.6)
			(layers "B.Cu" "B.Mask" "B.Paste")
			(roundrect_rratio 0.25)
			(net 23 "GND")
			(pinfunction "A")
			(pintype "passive")
		)
	)
	(footprint "antmicro-footprints:TP_SMD_0.75mm"
		(layer "B.Cu")
		(at 149 65 180)
		(property "Reference" "TP20"
			(at 0.6 -0.4 0)
			(layer "B.SilkS")
			(effects
				(font
					(size 0.7 0.7)
					(thickness 0.15)
				)
				(justify left bottom mirror)
			)
		)
		(property "Value" "TP_0.75mm_SMD"
			(at 0 -1.2 0)
			(layer "B.Fab")
			(effects
				(font
					(size 0.7 0.7)
					(thickness 0.15)
				)
				(justify left bottom mirror)
			)
		)
		(property "Description" "SMT test point"
			(at 0 0 0)
			(layer "B.Fab")
			(hide yes)
			(effects
				(font
					(size 1.27 1.27)
					(thickness 0.15)
				)
				(justify mirror)
			)
		)
		(property "MPN" ""
			(at 0 0 180)
			(unlocked yes)
			(layer "B.Fab")
			(hide yes)
			(effects
				(font
					(size 1 1)
					(thickness 0.15)
				)
				(justify mirror)
			)
		)
		(property "Manufacturer" ""
			(at 0 0 180)
			(unlocked yes)
			(layer "B.Fab")
			(hide yes)
			(effects
				(font
					(size 1 1)
					(thickness 0.15)
				)
				(justify mirror)
			)
		)
		(property "Author" "Antmicro"
			(at 0 0 180)
			(unlocked yes)
			(layer "B.Fab")
			(hide yes)
			(effects
				(font
					(size 1 1)
					(thickness 0.15)
				)
				(justify mirror)
			)
		)
		(property "License" "Apache-2.0"
			(at 0 0 180)
			(unlocked yes)
			(layer "B.Fab")
			(hide yes)
			(effects
				(font
					(size 1 1)
					(thickness 0.15)
				)
				(justify mirror)
			)
		)
		(sheetname "/X710-AT2 power/")
		(sheetfile "x710-at2-power.kicad_sch")
		(attr exclude_from_pos_files exclude_from_bom)
		(fp_circle
			(center 0 0)
			(end 0.475 0)
			(stroke
				(width 0.05)
				(type default)
			)
			(fill no)
			(layer "B.CrtYd")
		)
		(fp_text user "Author: Antmicro"
			(at -0.4 -3.901 0)
			(layer "B.Fab")
			(effects
				(font
					(size 0.7 0.7)
					(thickness 0.15)
				)
				(justify left bottom mirror)
			)
		)
		(fp_text user "${REFERENCE}"
			(at -0.4 -2.7 0)
			(layer "B.Fab")
			(effects
				(font
					(size 0.7 0.7)
					(thickness 0.15)
				)
				(justify left bottom mirror)
			)
		)
		(fp_text user "License: Apache-2.0"
			(at -0.4 -5.101 0)
			(layer "B.Fab")
			(effects
				(font
					(size 0.7 0.7)
					(thickness 0.15)
				)
				(justify left bottom mirror)
			)
		)
		(pad "1" smd circle
			(at 0 0 180)
			(size 0.75 0.75)
			(layers "B.Cu" "B.Mask")
			(net 1 "VCCA")
			(pinfunction "1")
			(pintype "passive")
		)
	)
	(footprint "antmicro-footprints:R_0402_1005Metric"
		(layer "B.Cu")
		(at 140.4 136.580998 180)
		(descr "Resistor SMD 0402")
		(tags "resistor SMD 0402")
		(property "Reference" "R12"
			(at -19.525001 8.1 0)
			(layer "B.SilkS")
			(effects
				(font
					(size 0.7 0.7)
					(thickness 0.15)
				)
				(justify mirror)
			)
		)
		(property "Value" "R_3k3_0402"
			(at -1.011843 -1.772047 0)
			(layer "B.Fab")
			(effects
				(font
					(size 0.7 0.7)
					(thickness 0.15)
				)
				(justify left bottom mirror)
			)
		)
		(property "Datasheet" "https://www.bourns.com/docs/product-datasheets/cr.pdf"
			(at 0 0 0)
			(layer "B.Fab")
			(hide yes)
			(effects
				(font
					(size 1.27 1.27)
					(thickness 0.15)
				)
				(justify mirror)
			)
		)
		(property "Description" "SMD Chip Resistor, 3.3 kohm, ± 1%, 63 mW, 0402 [1005 Metric], Thick Film, General Purpose"
			(at 0 0 0)
			(layer "B.Fab")
			(hide yes)
			(effects
				(font
					(size 1.27 1.27)
					(thickness 0.15)
				)
				(justify mirror)
			)
		)
		(property "MPN" "CR0402-FX-3301GLF"
			(at 0 0 180)
			(unlocked yes)
			(layer "B.Fab")
			(hide yes)
			(effects
				(font
					(size 1 1)
					(thickness 0.15)
				)
				(justify mirror)
			)
		)
		(property "Manufacturer" "Bourns"
			(at 0 0 180)
			(unlocked yes)
			(layer "B.Fab")
			(hide yes)
			(effects
				(font
					(size 1 1)
					(thickness 0.15)
				)
				(justify mirror)
			)
		)
		(property "License" "Apache-2.0"
			(at 0 0 180)
			(unlocked yes)
			(layer "B.Fab")
			(hide yes)
			(effects
				(font
					(size 1 1)
					(thickness 0.15)
				)
				(justify mirror)
			)
		)
		(property "Val" "3k3"
			(at 0 0 180)
			(unlocked yes)
			(layer "B.Fab")
			(hide yes)
			(effects
				(font
					(size 1 1)
					(thickness 0.15)
				)
				(justify mirror)
			)
		)
		(property "Tolerance" "1%"
			(at 0 0 180)
			(unlocked yes)
			(layer "B.Fab")
			(hide yes)
			(effects
				(font
					(size 1 1)
					(thickness 0.15)
				)
				(justify mirror)
			)
		)
		(property "Author" "Antmicro"
			(at 0 0 180)
			(unlocked yes)
			(layer "B.Fab")
			(hide yes)
			(effects
				(font
					(size 1 1)
					(thickness 0.15)
				)
				(justify mirror)
			)
		)
		(sheetname "/PD and TB DC-DC/")
		(sheetfile "PD_and_TB_DC_DC.kicad_sch")
		(attr smd)
		(fp_rect
			(start -0.925 0.47)
			(end 0.925 -0.47)
			(stroke
				(width 0.05)
				(type default)
			)
			(fill no)
			(layer "B.CrtYd")
		)
		(fp_rect
			(start -0.5 0.25)
			(end 0.5 -0.25)
			(stroke
				(width 0.15)
				(type solid)
			)
			(fill no)
			(layer "B.Fab")
		)
		(fp_text user "Author: Antmicro"
			(at -0.95 -4.169 0)
			(layer "B.Fab")
			(effects
				(font
					(size 0.7 0.7)
					(thickness 0.15)
				)
				(justify left bottom mirror)
			)
		)
		(fp_text user "License: Apache-2.0"
			(at -0.95 -5.169 0)
			(layer "B.Fab")
			(effects
				(font
					(size 0.7 0.7)
					(thickness 0.15)
				)
				(justify left bottom mirror)
			)
		)
		(fp_text user "${REFERENCE}"
			(at -0.95 -3.168 0)
			(layer "B.Fab")
			(effects
				(font
					(size 0.7 0.7)
					(thickness 0.15)
				)
				(justify left bottom mirror)
			)
		)
		(pad "1" smd roundrect
			(at -0.48 0 180)
			(size 0.59 0.64)
			(layers "B.Cu" "B.Mask" "B.Paste")
			(roundrect_rratio 0.25)
			(net 304 "/PD and TB DC-DC/TPS_3V3")
			(pintype "passive")
		)
		(pad "2" smd roundrect
			(at 0.48 0 180)
			(size 0.59 0.64)
			(layers "B.Cu" "B.Mask" "B.Paste")
			(roundrect_rratio 0.25)
			(net 198 "Net-(U3-I2C_SDA2)")
			(pintype "passive")
		)
	)
)
